# T6G (Grand Teton) — schematic netlist excerpt (pin names and nets, part order shuffled) for the footprints in the layout excerpt that follows; sources: Cadence DE-HDL packaged netlist, KiCad conversion of 04192023_DAF0TMB3IC0_F0TG_MB_C_brd_V02_OCP.brd

C289  Q_CAP  1UF 4V 20% X6S  pkg 0201  page 334 : A = P0V9_CPU1_RT1_2A ; B = GND
PR2510  Q_RES  1 1% CHIP  pkg 0402LF  page 266 : A = P12V_HSC_ADC_P ; B = P12V_HSC_SENSE2_R1_P
R362  Q_RES  1K 1% CHIP  pkg 0402LF  page 161 : A = PVDD11_S3_P1 ; B = SMB_APML_CPU1_SCL

(kicad_pcb
	(version 20260206)
	(generator "pcbnew")
	(generator_version "10.0")
	(general
		(thickness 1.6)
		(legacy_teardrops no)
	)
	(paper "A4")
	(title_block
		(title "04192023_DAF0TMB3IC0_F0TG_MB_C_brd_V02_OCP.brd")
		(comment 1 "Grand Teton / footprints 6387-6389 of 8354")
	)
	(layers
		(0 "F.Cu" signal "TOP")
		(4 "In1.Cu" signal "GND")
		(6 "In2.Cu" signal "IN1")
		(8 "In3.Cu" signal "GND1")
		(10 "In4.Cu" signal "IN2")
		(12 "In5.Cu" signal "GND2")
		(14 "In6.Cu" signal "IN3")
		(16 "In7.Cu" signal "GND3")
		(18 "In8.Cu" signal "VCC")
		(20 "In9.Cu" signal "VCC1")
		(22 "In10.Cu" signal "GND4")
		(24 "In11.Cu" signal "IN4")
		(26 "In12.Cu" signal "GND5")
		(28 "In13.Cu" signal "IN5")
		(30 "In14.Cu" signal "GND6")
		(32 "In15.Cu" signal "IN6")
		(34 "In16.Cu" signal "GND7")
		(2 "B.Cu" signal "BOTTOM")
		(9 "F.Adhes" user "F.Adhesive")
		(11 "B.Adhes" user "B.Adhesive")
		(13 "F.Paste" user "Package Geometry/Pastemask Top")
		(15 "B.Paste" user "Package Geometry/Pastemask Bottom")
		(5 "F.SilkS" user "Ref Des/Silkscreen Top")
		(7 "B.SilkS" user "Ref Des/Silkscreen Bottom")
		(1 "F.Mask" user "Board Geometry/Soldermask Top")
		(3 "B.Mask" user "Board Geometry/Soldermask Bottom")
		(17 "Dwgs.User" user "User.Drawings")
		(19 "Cmts.User" user "User.Comments")
		(21 "Eco1.User" user "User.Eco1")
		(23 "Eco2.User" user "User.Eco2")
		(25 "Edge.Cuts" user "Board Geometry/Outline")
		(27 "Margin" user)
		(31 "F.CrtYd" user "Package Geometry/Place Bound Top")
		(29 "B.CrtYd" user "Package Geometry/Place Bound Bottom")
		(35 "F.Fab" user "Ref Des/Assembly Top")
		(33 "B.Fab" user "Ref Des/Assembly Bottom")
	)
	(footprint ""
		(layer "B.Cu")
		(at 208.461356 -377.666504)
		(property "Reference" "PR2510"
			(at 0 0 0)
			(layer "B.SilkS")
			(hide yes)
			(effects
				(font
					(size 1.27 1.27)
				)
				(justify mirror)
			)
		)
		(property "Value" ""
			(at 0 0 0)
			(layer "B.Fab")
			(effects
				(font
					(size 1.27 1.27)
				)
				(justify mirror)
			)
		)
		(duplicate_pad_numbers_are_jumpers no)
		(fp_line
			(start -0.7874 -0.4064)
			(end -0.7874 0.4064)
			(stroke
				(width 0.1524)
				(type default)
			)
			(layer "B.SilkS")
		)
		(fp_line
			(start -0.7874 0.4064)
			(end 0.7874 0.4064)
			(stroke
				(width 0.1524)
				(type default)
			)
			(layer "B.SilkS")
		)
		(fp_line
			(start 0.7874 -0.4064)
			(end -0.7874 -0.4064)
			(stroke
				(width 0.1524)
				(type default)
			)
			(layer "B.SilkS")
		)
		(fp_line
			(start 0.7874 0.4064)
			(end 0.7874 -0.4064)
			(stroke
				(width 0.1524)
				(type default)
			)
			(layer "B.SilkS")
		)
		(fp_line
			(start -0.67945 -0.3048)
			(end -0.67945 0.3048)
			(stroke
				(width 0.1)
				(type default)
			)
			(layer "B.Fab")
		)
		(fp_line
			(start -0.67945 0.3048)
			(end -0.120396 0.3048)
			(stroke
				(width 0.1)
				(type default)
			)
			(layer "B.Fab")
		)
		(fp_line
			(start -0.12065 -0.3048)
			(end -0.67945 -0.3048)
			(stroke
				(width 0.1)
				(type default)
			)
			(layer "B.Fab")
		)
		(fp_line
			(start -0.12065 -0.2794)
			(end -0.12065 -0.3048)
			(stroke
				(width 0.1)
				(type default)
			)
			(layer "B.Fab")
		)
		(fp_line
			(start -0.120396 0.2794)
			(end 0.12065 0.2794)
			(stroke
				(width 0.1)
				(type default)
			)
			(layer "B.Fab")
		)
		(fp_line
			(start -0.120396 0.3048)
			(end -0.120396 0.2794)
			(stroke
				(width 0.1)
				(type default)
			)
			(layer "B.Fab")
		)
		(fp_line
			(start 0.12065 -0.305054)
			(end 0.12065 -0.2794)
			(stroke
				(width 0.1)
				(type default)
			)
			(layer "B.Fab")
		)
		(fp_line
			(start 0.12065 -0.2794)
			(end -0.12065 -0.2794)
			(stroke
				(width 0.1)
				(type default)
			)
			(layer "B.Fab")
		)
		(fp_line
			(start 0.12065 0.2794)
			(end 0.12065 0.3048)
			(stroke
				(width 0.1)
				(type default)
			)
			(layer "B.Fab")
		)
		(fp_line
			(start 0.12065 0.3048)
			(end 0.67945 0.3048)
			(stroke
				(width 0.1)
				(type default)
			)
			(layer "B.Fab")
		)
		(fp_line
			(start 0.67945 -0.305054)
			(end 0.12065 -0.305054)
			(stroke
				(width 0.1)
				(type default)
			)
			(layer "B.Fab")
		)
		(fp_line
			(start 0.67945 0.3048)
			(end 0.67945 -0.305054)
			(stroke
				(width 0.1)
				(type default)
			)
			(layer "B.Fab")
		)
		(pad "1" smd circle
			(at 0.40005 0 180)
			(size 0 0)
			(layers "B.Cu" "B.Mask" "B.Paste")
			(net "P12V_HSC_ADC_P")
		)
		(pad "2" smd circle
			(at -0.40005 0 180)
			(size 0 0)
			(layers "B.Cu" "B.Mask" "B.Paste")
			(net "P12V_HSC_SENSE2_R1_P")
		)
	)
	(footprint ""
		(layer "B.Cu")
		(at 236.855 -240.411 -90)
		(property "Reference" "R362"
			(at 0 0 90)
			(layer "B.SilkS")
			(hide yes)
			(effects
				(font
					(size 1.27 1.27)
				)
				(justify mirror)
			)
		)
		(property "Value" ""
			(at 0 0 90)
			(layer "B.Fab")
			(effects
				(font
					(size 1.27 1.27)
				)
				(justify mirror)
			)
		)
		(duplicate_pad_numbers_are_jumpers no)
		(fp_line
			(start -0.7874 0.4064)
			(end 0.7874 0.4064)
			(stroke
				(width 0.1524)
				(type default)
			)
			(layer "B.SilkS")
		)
		(fp_line
			(start 0.7874 0.4064)
			(end 0.7874 -0.4064)
			(stroke
				(width 0.1524)
				(type default)
			)
			(layer "B.SilkS")
		)
		(fp_line
			(start -0.7874 -0.4064)
			(end -0.7874 0.4064)
			(stroke
				(width 0.1524)
				(type default)
			)
			(layer "B.SilkS")
		)
		(fp_line
			(start 0.7874 -0.4064)
			(end -0.7874 -0.4064)
			(stroke
				(width 0.1524)
				(type default)
			)
			(layer "B.SilkS")
		)
		(fp_line
			(start -0.67945 0.3048)
			(end -0.120396 0.3048)
			(stroke
				(width 0.1)
				(type default)
			)
			(layer "B.Fab")
		)
		(fp_line
			(start -0.120396 0.3048)
			(end -0.120396 0.2794)
			(stroke
				(width 0.1)
				(type default)
			)
			(layer "B.Fab")
		)
		(fp_line
			(start 0.12065 0.3048)
			(end 0.67945 0.3048)
			(stroke
				(width 0.1)
				(type default)
			)
			(layer "B.Fab")
		)
		(fp_line
			(start 0.67945 0.3048)
			(end 0.67945 -0.305054)
			(stroke
				(width 0.1)
				(type default)
			)
			(layer "B.Fab")
		)
		(fp_line
			(start -0.120396 0.2794)
			(end 0.12065 0.2794)
			(stroke
				(width 0.1)
				(type default)
			)
			(layer "B.Fab")
		)
		(fp_line
			(start 0.12065 0.2794)
			(end 0.12065 0.3048)
			(stroke
				(width 0.1)
				(type default)
			)
			(layer "B.Fab")
		)
		(fp_line
			(start -0.12065 -0.2794)
			(end -0.12065 -0.3048)
			(stroke
				(width 0.1)
				(type default)
			)
			(layer "B.Fab")
		)
		(fp_line
			(start 0.12065 -0.2794)
			(end -0.12065 -0.2794)
			(stroke
				(width 0.1)
				(type default)
			)
			(layer "B.Fab")
		)
		(fp_line
			(start -0.67945 -0.3048)
			(end -0.67945 0.3048)
			(stroke
				(width 0.1)
				(type default)
			)
			(layer "B.Fab")
		)
		(fp_line
			(start -0.12065 -0.3048)
			(end -0.67945 -0.3048)
			(stroke
				(width 0.1)
				(type default)
			)
			(layer "B.Fab")
		)
		(fp_line
			(start 0.12065 -0.305054)
			(end 0.12065 -0.2794)
			(stroke
				(width 0.1)
				(type default)
			)
			(layer "B.Fab")
		)
		(fp_line
			(start 0.67945 -0.305054)
			(end 0.12065 -0.305054)
			(stroke
				(width 0.1)
				(type default)
			)
			(layer "B.Fab")
		)
		(pad "1" smd circle
			(at 0.40005 0 90)
			(size 0 0)
			(layers "B.Cu" "B.Mask" "B.Paste")
			(net "PVDD11_S3_P1")
		)
		(pad "2" smd circle
			(at -0.40005 0 90)
			(size 0 0)
			(layers "B.Cu" "B.Mask" "B.Paste")
			(net "SMB_APML_CPU1_SCL")
		)
	)
	(footprint ""
		(layer "B.Cu")
		(at 97.906332 -386.766562 90)
		(property "Reference" "C289"
			(at 0 0 90)
			(layer "B.SilkS")
			(hide yes)
			(effects
				(font
					(size 1.27 1.27)
				)
				(justify mirror)
			)
		)
		(property "Value" ""
			(at 0 0 90)
			(layer "B.Fab")
			(effects
				(font
					(size 1.27 1.27)
				)
				(justify mirror)
			)
		)
		(duplicate_pad_numbers_are_jumpers no)
		(fp_line
			(start 0.299974 -0.150114)
			(end -0.299974 -0.150114)
			(stroke
				(width 0.1)
				(type default)
			)
			(layer "B.Fab")
		)
		(fp_line
			(start -0.299974 -0.150114)
			(end -0.299974 0.150114)
			(stroke
				(width 0.1)
				(type default)
			)
			(layer "B.Fab")
		)
		(fp_line
			(start 0.299974 0.150114)
			(end 0.299974 -0.150114)
			(stroke
				(width 0.1)
				(type default)
			)
			(layer "B.Fab")
		)
		(fp_line
			(start -0.299974 0.150114)
			(end 0.299974 0.150114)
			(stroke
				(width 0.1)
				(type default)
			)
			(layer "B.Fab")
		)
		(pad "1" smd rect
			(at 0.2667 0 270)
			(size 0.3048 0.381)
			(layers "B.Cu" "B.Mask" "B.Paste")
			(net "P0V9_CPU1_RT1_2A")
		)
		(pad "2" smd rect
			(at -0.2667 0 270)
			(size 0.3048 0.381)
			(layers "B.Cu" "B.Mask" "B.Paste")
			(net "GND")
		)
	)
)
